FILE_TYPE = MULTI_PHYS_TABLE;

PART '74LVC1G66GV'

{========================================================================================}
:VALUE         | PART_TYPE | MATERIAL | PART_NUMBER    = STANDARD | LIFECYCLE | PART_NUMBER   | JEDEC_TYPE | DESCRIPTION                  | MANUFTR | MANUF_PN      | RD_CMPLS_LVL | CMPLS_LVL | FROM_PJ     | CLASS | DIP_SMD | DATA                | EE_CHECK_LIST | FP_ECN | PSL | CREATOR | STATUS | CREATEDAY  ;
{========================================================================================}
 '74LVC1G66GV' | 'SMLF'    | 'IC'     | 'AL001G66000'(!) = ''       | ''        | 'AL001G66000' |'SC74AXA'| 'IC(5P) 74LVC1G66GV(SOT753)' | 'PHI'   | '74LVC1G66GV' | ''           | 'EP'      | 'S4P-FRANK' | 'IC'  | ''      | 'PHI_74LVC1G66.pdf' | 'SC74AXA.xls' | ''     | ''  | ''      | ''     | '20140912'
 '74LVC1G66GV' | 'SMLF'    | 'EMPTY'  | 'AL001G66000'(!) = ''       | ''        | 'AL001G66000' |'SC74AXA'| 'IC(5P) 74LVC1G66GV(SOT753)' | 'PHI'   | '74LVC1G66GV' | ''           | 'EP'      | 'S4P-FRANK' | 'IC'  | ''      | 'PHI_74LVC1G66.pdf' | 'SC74AXA.xls' | ''     | ''  | ''      | ''     | '20140912'

END_PART

END.

